(kicad_pcb
	(version 20221018)
	(generator pcbnew)
	(general
    (thickness 1.518)
  )
	(paper "A4")
	(title_block
    (title "Kria K26 Devboard")
    (date "2024-03-26")
    (rev "1.2.5")
    (comment 1 "www.antmicro.com")
    (comment 2 "Antmicro Ltd.")
		(comment 9 "footprints 83-89 of 660")
	)
	(layers
    (0 "F.Cu" mixed)
    (1 "In1.Cu" power)
    (2 "In2.Cu" mixed)
    (3 "In3.Cu" power)
    (4 "In4.Cu" mixed)
    (5 "In5.Cu" power)
    (6 "In6.Cu" mixed)
    (31 "B.Cu" power)
    (32 "B.Adhes" user "B.Adhesive")
    (33 "F.Adhes" user "F.Adhesive")
    (34 "B.Paste" user)
    (35 "F.Paste" user)
    (36 "B.SilkS" user "B.Silkscreen")
    (37 "F.SilkS" user "F.Silkscreen")
    (38 "B.Mask" user)
    (39 "F.Mask" user)
    (40 "Dwgs.User" user "User.Drawings")
    (41 "Cmts.User" user "User.Comments")
    (42 "Eco1.User" user "User.Eco1")
    (43 "Eco2.User" user "User.Eco2")
    (44 "Edge.Cuts" user)
    (45 "Margin" user)
    (46 "B.CrtYd" user "B.Courtyard")
    (47 "F.CrtYd" user "F.Courtyard")
    (48 "B.Fab" user)
    (49 "F.Fab" user)
  )
	(footprint "kria-k26-devboard-footprints:QFN-14-1EP_2.5x3mm_EP1.15x1.65mm_ONSemi_MLP14A" (layer "F.Cu")
    (at 112.35 141.1 180)
    (descr "https://www.onsemi.cn/pub/Collateral/510CB.PDF")
    (property "Author" "Antmicro")
    (property "License" "Apache-2.0")
    (property "MPN" "74LCX07BQX")
    (property "Manufacturer" "ON Semiconductor")
    (property "Sheetfile" "reset.kicad_sch")
    (property "Sheetname" "Reset logic")
    (property "ki_description" "Buffer, Non-Inverting 6 Element 1 Bit per Element Open Drain Output 14-DQFN (3x2.5)")
    (property "ki_keywords" "SMT, LOGIC, IC, DRIVER")
    (attr smd)
    (fp_text reference "U36" (at -0.52 1.77 180) (layer "F.SilkS")
        (effects (font (size 0.7 0.7) (thickness 0.15)) (justify left bottom))
    )
    (fp_text value "74LCX07_QFN" (at 0 2.9 180) (layer "F.Fab") hide
        (effects (font (size 0.7 0.7) (thickness 0.15)) (justify left bottom))
    )
    (fp_text user "Author: Antmicro" (at -1.75 5.541 180) (layer "F.Fab") hide
        (effects (font (size 0.7 0.7) (thickness 0.15)) (justify left bottom))
    )
    (fp_text user "${REFERENCE}" (at -1.75 4.291 180) (layer "F.Fab") hide
        (effects (font (size 0.7 0.7) (thickness 0.15)) (justify left bottom))
    )
    (fp_text user "License: Apache-2.0" (at -1.75 6.791 180) (layer "F.Fab") hide
        (effects (font (size 0.7 0.7) (thickness 0.15)) (justify left bottom))
    )
    (fp_poly
      (pts
        (xy -0.382 -0.697)
        (xy 0.378 -0.697)
        (xy 0.378 -0.066)
        (xy -0.382 -0.066)
      )

      (stroke (width 0.01) (type solid)) (fill solid) (layer "F.Paste"))
    (fp_poly
      (pts
        (xy -0.382 0.063)
        (xy 0.378 0.063)
        (xy 0.378 0.693)
        (xy -0.382 0.693)
      )

      (stroke (width 0.01) (type solid)) (fill solid) (layer "F.Paste"))
    (fp_line (start -1.28 -1.53) (end -1.28 -1.25)
      (stroke (width 0.15) (type solid)) (layer "F.SilkS"))
    (fp_line (start -1.28 1.241) (end -1.279 1.532)
      (stroke (width 0.15) (type solid)) (layer "F.SilkS"))
    (fp_line (start -0.49 1.532) (end -1.279 1.532)
      (stroke (width 0.15) (type solid)) (layer "F.SilkS"))
    (fp_line (start 0.49 -1.532) (end 1.279 -1.532)
      (stroke (width 0.15) (type solid)) (layer "F.SilkS"))
    (fp_line (start 0.49 1.532) (end 1.279 1.532)
      (stroke (width 0.15) (type solid)) (layer "F.SilkS"))
    (fp_line (start 1.28 -1.24) (end 1.279 -1.532)
      (stroke (width 0.15) (type solid)) (layer "F.SilkS"))
    (fp_line (start 1.28 1.241) (end 1.279 1.532)
      (stroke (width 0.15) (type solid)) (layer "F.SilkS"))
    (fp_circle (center -0.7 -1.81) (end -0.65 -1.81)
      (stroke (width 0.15) (type solid)) (fill none) (layer "F.SilkS"))
    (fp_rect (start -1.75 -2.01) (end 1.75 1.98)
      (stroke (width 0.05) (type solid)) (fill none) (layer "F.CrtYd"))
    (fp_line (start -1.281 -1.532) (end 1.279 -1.532)
      (stroke (width 0.15) (type solid)) (layer "F.Fab"))
    (fp_line (start -1.281 1.531) (end -1.281 -1.532)
      (stroke (width 0.15) (type solid)) (layer "F.Fab"))
    (fp_line (start 1.279 -1.532) (end 1.279 1.531)
      (stroke (width 0.15) (type solid)) (layer "F.Fab"))
    (fp_line (start 1.279 1.531) (end -1.281 1.531)
      (stroke (width 0.15) (type solid)) (layer "F.Fab"))
    (pad "1" smd roundrect (at -0.25 -1.46 270) (size 0.78 0.27) (layers "F.Cu" "F.Paste" "F.Mask") (roundrect_rratio 0.07)
      (net 676 "Net-(U34-A_{1})") (pintype "input"))
    (pad "2" smd roundrect (at -1.21 -1) (size 0.78 0.27) (layers "F.Cu" "F.Paste" "F.Mask") (roundrect_rratio 0.07)
      (net 221 "/PCIE M2 key E /~{M2_PERST}") (pintype "open_collector"))
    (pad "3" smd roundrect (at -1.21 -0.501) (size 0.78 0.27) (layers "F.Cu" "F.Paste" "F.Mask") (roundrect_rratio 0.07)
      (net 679 "Net-(U33-2A2)") (pintype "input"))
    (pad "4" smd roundrect (at -1.21 0) (size 0.78 0.27) (layers "F.Cu" "F.Paste" "F.Mask") (roundrect_rratio 0.07)
      (net 176 "/Ethernet/~{ETH_RESET}") (pintype "open_collector"))
    (pad "5" smd roundrect (at -1.21 0.499) (size 0.78 0.27) (layers "F.Cu" "F.Paste" "F.Mask") (roundrect_rratio 0.07)
      (net 678 "Net-(U33-2A1)") (pintype "input"))
    (pad "6" smd roundrect (at -1.21 0.999) (size 0.78 0.27) (layers "F.Cu" "F.Paste" "F.Mask") (roundrect_rratio 0.07)
      (net 175 "/Reset logic/~{USB_HUB_RESET}") (pintype "open_collector"))
    (pad "7" smd roundrect (at -0.25 1.459 90) (size 0.78 0.27) (layers "F.Cu" "F.Paste" "F.Mask") (roundrect_rratio 0.07)
      (net 1 "GND") (pinfunction "GND") (pintype "power_in"))
    (pad "8" smd roundrect (at 0.248 1.459 90) (size 0.78 0.27) (layers "F.Cu" "F.Paste" "F.Mask") (roundrect_rratio 0.07)
      (net 178 "/Reset logic/~{USB_PHY_RESET}") (pintype "open_collector"))
    (pad "9" smd roundrect (at 1.209 0.999 180) (size 0.78 0.27) (layers "F.Cu" "F.Paste" "F.Mask") (roundrect_rratio 0.07)
      (net 677 "Net-(U33-1A2)") (pintype "input"))
    (pad "10" smd roundrect (at 1.209 0.499 180) (size 0.78 0.27) (layers "F.Cu" "F.Paste" "F.Mask") (roundrect_rratio 0.07)
      (net 177 "/Reset logic/~{SD_CARD_RESET}") (pintype "open_collector"))
    (pad "11" smd roundrect (at 1.209 0 180) (size 0.78 0.27) (layers "F.Cu" "F.Paste" "F.Mask") (roundrect_rratio 0.07)
      (net 675 "Net-(U33-1A1)") (pintype "input"))
    (pad "12" smd roundrect (at 1.209 -0.501 180) (size 0.78 0.27) (layers "F.Cu" "F.Paste" "F.Mask") (roundrect_rratio 0.07)
      (net 800 "unconnected-(U36-Pad12)") (pintype "open_collector+no_connect"))
    (pad "13" smd roundrect (at 1.209 -1 180) (size 0.78 0.27) (layers "F.Cu" "F.Paste" "F.Mask") (roundrect_rratio 0.07)
      (net 801 "unconnected-(U36-Pad13)") (pintype "input+no_connect"))
    (pad "14" smd roundrect (at 0.248 -1.46 270) (size 0.78 0.27) (layers "F.Cu" "F.Paste" "F.Mask") (roundrect_rratio 0.07)
      (net 15 "PS_3V3") (pinfunction "VCC") (pintype "power_in"))
    (pad "15" smd rect (at -0.002 0 270) (size 1.65 1.15) (layers "F.Cu" "F.Mask")
      (net 733 "unconnected-(U36G-DAP-Pad15)") (pinfunction "DAP") (pintype "no_connect"))
  )
	(footprint "kria-k26-devboard-footprints:SOT-23-5" (layer "F.Cu")
    (at 97.675 141.675001 90)
    (property "Author" "Antmicro")
    (property "License" "Apache-2.0")
    (property "MPN" "TPS3840PH30DBVR")
    (property "Manufacturer" "Texas Instruments")
    (property "Sheetfile" "reset.kicad_sch")
    (property "Sheetname" "Reset logic")
    (property "ki_description" "Voltage supervisor")
    (property "ki_keywords" "SMT, PMIC, IC, CONTROLLER")
    (attr smd)
    (fp_text reference "U32" (at 0.865001 0.405 90) (layer "F.SilkS")
        (effects (font (size 0.7 0.7) (thickness 0.15)) (justify left bottom))
    )
    (fp_text value "TPS3840PH30DBVR" (at 0.002 2.799 90) (layer "F.Fab") hide
        (effects (font (size 0.7 0.7) (thickness 0.15)) (justify left bottom))
    )
    (fp_text user "${REFERENCE}" (at -1.898 4.299 90) (layer "F.Fab") hide
        (effects (font (size 0.7 0.7) (thickness 0.15)) (justify left bottom))
    )
    (fp_text user "License: Apache-2.0" (at -1.898 6.7 90) (layer "F.Fab") hide
        (effects (font (size 0.7 0.7) (thickness 0.15)) (justify left bottom))
    )
    (fp_text user "Author: Antmicro" (at -1.898 5.499 90) (layer "F.Fab") hide
        (effects (font (size 0.7 0.7) (thickness 0.15)) (justify left bottom))
    )
    (fp_line (start -0.85 1.6) (end -0.85 1.301)
      (stroke (width 0.15) (type solid)) (layer "F.SilkS"))
    (fp_line (start -0.8 -1.6) (end -0.8 -1.3)
      (stroke (width 0.15) (type solid)) (layer "F.SilkS"))
    (fp_line (start -0.8 -1.6) (end -0.5 -1.6)
      (stroke (width 0.15) (type solid)) (layer "F.SilkS"))
    (fp_line (start -0.55 1.6) (end -0.85 1.6)
      (stroke (width 0.15) (type solid)) (layer "F.SilkS"))
    (fp_line (start 0.8 -1.6) (end 0.5 -1.6)
      (stroke (width 0.15) (type solid)) (layer "F.SilkS"))
    (fp_line (start 0.8 -1.3) (end 0.8 -1.6)
      (stroke (width 0.15) (type solid)) (layer "F.SilkS"))
    (fp_line (start 0.8 0.55) (end 0.8 -0.55)
      (stroke (width 0.15) (type solid)) (layer "F.SilkS"))
    (fp_line (start 0.8 1.3) (end 0.8 1.599)
      (stroke (width 0.15) (type solid)) (layer "F.SilkS"))
    (fp_line (start 0.8 1.599) (end 0.549 1.599)
      (stroke (width 0.15) (type solid)) (layer "F.SilkS"))
    (fp_circle (center -1.25 -1.5) (end -1.2 -1.5)
      (stroke (width 0.15) (type solid)) (fill solid) (layer "F.SilkS"))
    (fp_rect (start 1.9 -1.76) (end -1.9 1.75)
      (stroke (width 0.05) (type solid)) (fill none) (layer "F.CrtYd"))
    (fp_line (start -0.398 -1.526) (end -0.874 -1.05)
      (stroke (width 0.15) (type solid)) (layer "F.Fab"))
    (fp_rect (start 0.874 1.523) (end -0.873 -1.525)
      (stroke (width 0.15) (type solid)) (fill none) (layer "F.Fab"))
    (pad "1" smd rect (at -1.351 -0.951) (size 0.55 1) (layers "F.Cu" "F.Paste" "F.Mask")
      (net 174 "/Reset logic/PL_RST") (pinfunction "RESET") (pintype "open_collector"))
    (pad "2" smd rect (at -1.351 0) (size 0.55 1) (layers "F.Cu" "F.Paste" "F.Mask")
      (net 20 "PL_3V3") (pinfunction "VDD") (pintype "power_in"))
    (pad "3" smd rect (at -1.351 0.949) (size 0.55 1) (layers "F.Cu" "F.Paste" "F.Mask")
      (net 1 "GND") (pinfunction "GND") (pintype "power_in"))
    (pad "4" smd rect (at 1.35 0.949) (size 0.55 1) (layers "F.Cu" "F.Paste" "F.Mask")
      (net 335 "Net-(U32-MR_N)") (pinfunction "MR_N") (pintype "input"))
    (pad "5" smd rect (at 1.35 -0.951) (size 0.55 1) (layers "F.Cu" "F.Paste" "F.Mask")
      (net 246 "Net-(U32-CT)") (pinfunction "CT") (pintype "input"))
  )
	(footprint "kria-k26-devboard-footprints:SOD-123FL" (layer "F.Cu")
    (at 150.2 62.34)
    (property "Author" "Antmicro")
    (property "License" "Apache-2.0")
    (property "MPN" "SMF4L15CA")
    (property "Manufacturer" "Infineon Technologies")
    (property "Sheetfile" "usbc-socket.kicad_sch")
    (property "Sheetname" "USB-C socket")
    (property "ki_description" "SD Suppressors / TVS Diodes TVS SMF4L 15V Bidirectional")
    (attr smd)
    (fp_text reference "D26" (at 2.28 0.29) (layer "F.SilkS")
        (effects (font (size 0.7 0.7) (thickness 0.15)) (justify left bottom))
    )
    (fp_text value "SMF4L15CA" (at 0 1.967) (layer "F.Fab") hide
        (effects (font (size 0.7 0.7) (thickness 0.15)) (justify left bottom))
    )
    (fp_text user "Author: Antmicro" (at -2.406 5.168) (layer "F.Fab") hide
        (effects (font (size 0.7 0.7) (thickness 0.15)) (justify left bottom))
    )
    (fp_text user "${REFERENCE}" (at -2.406 3.967) (layer "F.Fab") hide
        (effects (font (size 0.7 0.7) (thickness 0.15)) (justify left bottom))
    )
    (fp_text user "License: Apache-2.0" (at -2.406 6.368) (layer "F.Fab") hide
        (effects (font (size 0.7 0.7) (thickness 0.15)) (justify left bottom))
    )
    (fp_line (start -2.3 -1.1) (end -2.3 1.1)
      (stroke (width 0.15) (type solid)) (layer "F.SilkS"))
    (fp_line (start -2.3 1.1) (end 0 1.1)
      (stroke (width 0.15) (type solid)) (layer "F.SilkS"))
    (fp_line (start 0 -1.1) (end -2.3 -1.1)
      (stroke (width 0.15) (type solid)) (layer "F.SilkS"))
    (fp_rect (start -2.35 -1.125) (end 2.35 1.125)
      (stroke (width 0.05) (type solid)) (fill none) (layer "F.CrtYd"))
    (fp_rect (start -1.825 -0.875) (end 1.824 0.873)
      (stroke (width 0.15) (type solid)) (fill none) (layer "F.Fab"))
    (fp_rect (start -0.775 -0.875) (end -0.525 0.875)
      (stroke (width 0.15) (type solid)) (fill solid) (layer "F.Fab"))
    (pad "1" smd roundrect (at -1.43 0) (size 1.34 1.8) (layers "F.Cu" "F.Paste" "F.Mask") (roundrect_rratio 0.14)
      (net 265 "/Debug and JTAG/USBC_VBUS") (pinfunction "1") (pintype "passive"))
    (pad "2" smd roundrect (at 1.429 0) (size 1.34 1.8) (layers "F.Cu" "F.Paste" "F.Mask") (roundrect_rratio 0.14)
      (net 1 "GND") (pinfunction "2") (pintype "passive"))
  )
	(footprint "kria-k26-devboard-footprints:SOD-123FL" (layer "F.Cu")
    (at 188.25 59.95)
    (property "Author" "Antmicro")
    (property "License" "Apache-2.0")
    (property "MPN" "SMF4L15CA")
    (property "Manufacturer" "Infineon Technologies")
    (property "Sheetfile" "dc-input.kicad_sch")
    (property "Sheetname" "DC Input")
    (property "ki_description" "SD Suppressors / TVS Diodes TVS SMF4L 15V Bidirectional")
    (attr smd)
    (fp_text reference "D27" (at 3.12 0.97 90) (layer "F.SilkS")
        (effects (font (size 0.7 0.7) (thickness 0.15)) (justify left bottom))
    )
    (fp_text value "SMF4L15CA" (at 0 1.967) (layer "F.Fab") hide
        (effects (font (size 0.7 0.7) (thickness 0.15)) (justify left bottom))
    )
    (fp_text user "License: Apache-2.0" (at -2.406 6.368) (layer "F.Fab") hide
        (effects (font (size 0.7 0.7) (thickness 0.15)) (justify left bottom))
    )
    (fp_text user "${REFERENCE}" (at -2.406 3.967) (layer "F.Fab") hide
        (effects (font (size 0.7 0.7) (thickness 0.15)) (justify left bottom))
    )
    (fp_text user "Author: Antmicro" (at -2.406 5.168) (layer "F.Fab") hide
        (effects (font (size 0.7 0.7) (thickness 0.15)) (justify left bottom))
    )
    (fp_line (start -2.3 -1.1) (end -2.3 1.1)
      (stroke (width 0.15) (type solid)) (layer "F.SilkS"))
    (fp_line (start -2.3 1.1) (end 0 1.1)
      (stroke (width 0.15) (type solid)) (layer "F.SilkS"))
    (fp_line (start 0 -1.1) (end -2.3 -1.1)
      (stroke (width 0.15) (type solid)) (layer "F.SilkS"))
    (fp_rect (start -2.35 -1.125) (end 2.35 1.125)
      (stroke (width 0.05) (type solid)) (fill none) (layer "F.CrtYd"))
    (fp_rect (start -1.825 -0.875) (end 1.824 0.873)
      (stroke (width 0.15) (type solid)) (fill none) (layer "F.Fab"))
    (fp_rect (start -0.775 -0.875) (end -0.525 0.875)
      (stroke (width 0.15) (type solid)) (fill solid) (layer "F.Fab"))
    (pad "1" smd roundrect (at -1.43 0) (size 1.34 1.8) (layers "F.Cu" "F.Paste" "F.Mask") (roundrect_rratio 0.14)
      (net 22 "/Power Supply/DC Input/DC_IN") (pinfunction "1") (pintype "passive"))
    (pad "2" smd roundrect (at 1.429 0) (size 1.34 1.8) (layers "F.Cu" "F.Paste" "F.Mask") (roundrect_rratio 0.14)
      (net 1 "GND") (pinfunction "2") (pintype "passive"))
  )
	(footprint "kria-k26-devboard-footprints:C_0402_1005Metric" (layer "F.Cu")
    (at 126.8 99 180)
    (descr "Capacitor SMD 0402")
    (tags "capacitor SMD 0402")
    (property "Author" "Antmicro")
    (property "Dielectric" "X5R")
    (property "License" "Apache-2.0")
    (property "MPN" "GRM155R61H104KE14D")
    (property "Manufacturer" "Murata")
    (property "Sheetfile" "usb.kicad_sch")
    (property "Sheetname" "USB")
    (property "Val" "100n")
    (property "Voltage" "50V")
    (property "ki_description" " ")
    (attr smd)
    (fp_text reference "C65" (at 1.15 -1.24 180) (layer "F.SilkS")
        (effects (font (size 0.7 0.7) (thickness 0.15)) (justify left bottom))
    )
    (fp_text value "C_100n_0402" (at 0 1.4 180) (layer "F.Fab") hide
        (effects (font (size 0.7 0.7) (thickness 0.15)) (justify left bottom))
    )
    (fp_text user "License: Apache-2.0" (at -0.932 5.17 180) (layer "F.Fab") hide
        (effects (font (size 0.7 0.7) (thickness 0.15)) (justify left bottom))
    )
    (fp_text user "${REFERENCE}" (at -0.932 3.168 180) (layer "F.Fab") hide
        (effects (font (size 0.7 0.7) (thickness 0.15)) (justify left bottom))
    )
    (fp_text user "Author: Antmicro" (at -0.932 4.17 180) (layer "F.Fab") hide
        (effects (font (size 0.7 0.7) (thickness 0.15)) (justify left bottom))
    )
    (fp_rect (start -0.94 -0.47) (end 0.94 0.47)
      (stroke (width 0.05) (type solid)) (fill none) (layer "F.CrtYd"))
    (fp_rect (start -0.499 -0.249) (end 0.499 0.249)
      (stroke (width 0.15) (type solid)) (fill none) (layer "F.Fab"))
    (pad "1" smd roundrect (at -0.484 0 180) (size 0.59 0.64) (layers "F.Cu" "F.Paste" "F.Mask") (roundrect_rratio 0.25)
      (net 17 "PS_1V8") (pintype "passive"))
    (pad "2" smd roundrect (at 0.484 0 180) (size 0.59 0.64) (layers "F.Cu" "F.Paste" "F.Mask") (roundrect_rratio 0.25)
      (net 1 "GND") (pintype "passive"))
  )
	(footprint "kria-k26-devboard-footprints:C_0402_1005Metric" (layer "F.Cu")
    (at 105.5 138.02 180)
    (descr "Capacitor SMD 0402")
    (tags "capacitor SMD 0402")
    (property "Author" "Antmicro")
    (property "Dielectric" "X5R")
    (property "License" "Apache-2.0")
    (property "MPN" "GRM155R61H104KE14D")
    (property "Manufacturer" "Murata")
    (property "Sheetfile" "i2c.kicad_sch")
    (property "Sheetname" "I2C ")
    (property "Val" "100n")
    (property "Voltage" "50V")
    (property "ki_description" " ")
    (attr smd)
    (fp_text reference "C35" (at 1.14 -1.41 180) (layer "F.SilkS")
        (effects (font (size 0.7 0.7) (thickness 0.15)) (justify left bottom))
    )
    (fp_text value "C_100n_0402" (at 0 1.4 180) (layer "F.Fab") hide
        (effects (font (size 0.7 0.7) (thickness 0.15)) (justify left bottom))
    )
    (fp_text user "License: Apache-2.0" (at -0.932 5.17 180) (layer "F.Fab") hide
        (effects (font (size 0.7 0.7) (thickness 0.15)) (justify left bottom))
    )
    (fp_text user "Author: Antmicro" (at -0.932 4.17 180) (layer "F.Fab") hide
        (effects (font (size 0.7 0.7) (thickness 0.15)) (justify left bottom))
    )
    (fp_text user "${REFERENCE}" (at -0.932 3.168 180) (layer "F.Fab") hide
        (effects (font (size 0.7 0.7) (thickness 0.15)) (justify left bottom))
    )
    (fp_rect (start -0.94 -0.47) (end 0.94 0.47)
      (stroke (width 0.05) (type solid)) (fill none) (layer "F.CrtYd"))
    (fp_rect (start -0.499 -0.249) (end 0.499 0.249)
      (stroke (width 0.15) (type solid)) (fill none) (layer "F.Fab"))
    (pad "1" smd roundrect (at -0.484 0 180) (size 0.59 0.64) (layers "F.Cu" "F.Paste" "F.Mask") (roundrect_rratio 0.25)
      (net 15 "PS_3V3") (pintype "passive"))
    (pad "2" smd roundrect (at 0.484 0 180) (size 0.59 0.64) (layers "F.Cu" "F.Paste" "F.Mask") (roundrect_rratio 0.25)
      (net 1 "GND") (pintype "passive"))
  )
	(footprint "kria-k26-devboard-footprints:R_0402_1005Metric" (layer "F.Cu")
    (at 105.5 137.075 180)
    (descr "Resistor SMD 0402")
    (tags "resistor SMD 0402")
    (property "Author" "Antmicro")
    (property "License" "Apache-2.0")
    (property "MPN" "CR0402-FX-1001GLF")
    (property "Manufacturer" "Bourns")
    (property "Sheetfile" "i2c.kicad_sch")
    (property "Sheetname" "I2C ")
    (property "Tolerance" "1%")
    (property "Val" "1k")
    (property "ki_description" "1k resistor in 0402 package with 1% tolerance")
    (attr smd)
    (fp_text reference "R36" (at -0.86 -0.995 180) (layer "F.SilkS")
        (effects (font (size 0.7 0.7) (thickness 0.15)) (justify left bottom))
    )
    (fp_text value "R_1k_0402" (at 0 1.4 180) (layer "F.Fab") hide
        (effects (font (size 0.7 0.7) (thickness 0.15)) (justify left bottom))
    )
    (fp_text user "Author: Antmicro" (at -0.95 4.169 180) (layer "F.Fab") hide
        (effects (font (size 0.7 0.7) (thickness 0.15)) (justify left bottom))
    )
    (fp_text user "License: Apache-2.0" (at -0.95 5.169 180) (layer "F.Fab") hide
        (effects (font (size 0.7 0.7) (thickness 0.15)) (justify left bottom))
    )
    (fp_text user "${REFERENCE}" (at -0.95 3.168 180) (layer "F.Fab") hide
        (effects (font (size 0.7 0.7) (thickness 0.15)) (justify left bottom))
    )
    (fp_rect (start -0.93 -0.47) (end 0.93 0.47)
      (stroke (width 0.05) (type solid)) (fill none) (layer "F.CrtYd"))
    (fp_rect (start -0.5 -0.25) (end 0.5 0.25)
      (stroke (width 0.15) (type solid)) (fill none) (layer "F.Fab"))
    (pad "1" smd roundrect (at -0.485 0 180) (size 0.59 0.64) (layers "F.Cu" "F.Paste" "F.Mask") (roundrect_rratio 0.25)
      (net 15 "PS_3V3") (pintype "passive"))
    (pad "2" smd roundrect (at 0.485 0 180) (size 0.59 0.64) (layers "F.Cu" "F.Paste" "F.Mask") (roundrect_rratio 0.25)
      (net 186 "/Debug and JTAG/~{EEPROM_WC}") (pintype "passive"))
  )
)
